(kicad_pcb
	(version 20240108)
	(generator "pcbnew")
	(generator_version "8.0")
	(general
		(thickness 1.62)
		(legacy_teardrops no)
	)
	(paper "A4")
	(title_block
		(title "Jetson Orin Baseboard")
		(date "2025-03-12")
		(rev "1.3.4")
		(company "Antmicro Ltd")
		(comment 1 "www.antmicro.com")
		(comment 9 "footprints 480-484 of 677")
	)
	(layers
		(0 "F.Cu" signal)
		(1 "In1.Cu" signal)
		(2 "In2.Cu" signal)
		(3 "In3.Cu" signal)
		(4 "In4.Cu" jumper)
		(5 "In5.Cu" signal)
		(6 "In6.Cu" signal)
		(31 "B.Cu" signal)
		(32 "B.Adhes" user "B.Adhesive")
		(33 "F.Adhes" user "F.Adhesive")
		(34 "B.Paste" user)
		(35 "F.Paste" user)
		(36 "B.SilkS" user "B.Silkscreen")
		(37 "F.SilkS" user "F.Silkscreen")
		(38 "B.Mask" user)
		(39 "F.Mask" user)
		(40 "Dwgs.User" user "User.Drawings")
		(41 "Cmts.User" user "User.Comments")
		(42 "Eco1.User" user "User.Eco1")
		(43 "Eco2.User" user "User.Eco2")
		(44 "Edge.Cuts" user)
		(45 "Margin" user)
		(46 "B.CrtYd" user "B.Courtyard")
		(47 "F.CrtYd" user "F.Courtyard")
		(48 "B.Fab" user)
		(49 "F.Fab" user)
	)
	(footprint "antmicro-footprints:DFN3538"
		(layer "B.Cu")
		(at 52.3 105.7 180)
		(property "Reference" "D13"
			(at 0 2.8 0)
			(unlocked yes)
			(layer "B.SilkS")
			(effects
				(font
					(size 0.7 0.7)
					(thickness 0.15)
				)
				(justify left bottom mirror)
			)
		)
		(property "Value" "CD-MMBL110S"
			(at 0 -3.5 0)
			(unlocked yes)
			(layer "B.Fab")
			(effects
				(font
					(size 0.7 0.7)
					(thickness 0.15)
				)
				(justify left bottom mirror)
			)
		)
		(property "Footprint" "antmicro-footprints:DFN3538"
			(at 0 0 180)
			(layer "F.Fab")
			(hide yes)
			(effects
				(font
					(size 1.27 1.27)
					(thickness 0.15)
				)
			)
		)
		(property "Datasheet" "https://www.bourns.com/docs/product-datasheets/CD-MMBL110S.pdf"
			(at 0 0 180)
			(layer "F.Fab")
			(hide yes)
			(effects
				(font
					(size 1.27 1.27)
					(thickness 0.15)
				)
			)
		)
		(property "Author" "Antmicro"
			(at 104.6 211.4 0)
			(layer "B.Fab")
			(hide yes)
			(effects
				(font
					(size 1 1)
					(thickness 0.15)
				)
				(justify mirror)
			)
		)
		(property "License" "Apache-2.0"
			(at 104.6 211.4 0)
			(layer "B.Fab")
			(hide yes)
			(effects
				(font
					(size 1 1)
					(thickness 0.15)
				)
				(justify mirror)
			)
		)
		(property "MPN" "CD-MMBL110S"
			(at 104.6 211.4 0)
			(layer "B.Fab")
			(hide yes)
			(effects
				(font
					(size 1 1)
					(thickness 0.15)
				)
				(justify mirror)
			)
		)
		(property "Manufacturer" "Bourns"
			(at 104.6 211.4 0)
			(layer "B.Fab")
			(hide yes)
			(effects
				(font
					(size 1 1)
					(thickness 0.15)
				)
				(justify mirror)
			)
		)
		(sheetname "Ethernet")
		(sheetfile "ethernet.kicad_sch")
		(attr smd)
		(fp_line
			(start 1.8 2)
			(end 1.6 2)
			(stroke
				(width 0.15)
				(type solid)
			)
			(layer "B.SilkS")
		)
		(fp_line
			(start 1.8 -2.05)
			(end 1.8 2)
			(stroke
				(width 0.15)
				(type solid)
			)
			(layer "B.SilkS")
		)
		(fp_line
			(start 1.8 -2.05)
			(end 1.6 -2.05)
			(stroke
				(width 0.15)
				(type solid)
			)
			(layer "B.SilkS")
		)
		(fp_line
			(start 0.95 2)
			(end -0.95 2)
			(stroke
				(width 0.15)
				(type solid)
			)
			(layer "B.SilkS")
		)
		(fp_line
			(start 0.95 -2.05)
			(end -0.95 -2.05)
			(stroke
				(width 0.15)
				(type solid)
			)
			(layer "B.SilkS")
		)
		(fp_line
			(start 0.748 2.15)
			(end 0.748 2.452)
			(stroke
				(width 0.15)
				(type solid)
			)
			(layer "B.SilkS")
		)
		(fp_line
			(start 0.598 2.301)
			(end 0.9 2.301)
			(stroke
				(width 0.15)
				(type solid)
			)
			(layer "B.SilkS")
		)
		(fp_line
			(start -0.6 2.25)
			(end -0.902 2.25)
			(stroke
				(width 0.15)
				(type solid)
			)
			(layer "B.SilkS")
		)
		(fp_line
			(start -1.6 -2.05)
			(end -1.8 -2.05)
			(stroke
				(width 0.15)
				(type solid)
			)
			(layer "B.SilkS")
		)
		(fp_line
			(start -1.8 -2.05)
			(end -1.8 1.5)
			(stroke
				(width 0.15)
				(type solid)
			)
			(layer "B.SilkS")
		)
		(fp_rect
			(start -2.1 2.6)
			(end 2.1 -2.6)
			(stroke
				(width 0.05)
				(type solid)
			)
			(fill none)
			(layer "B.CrtYd")
		)
		(fp_line
			(start -1.801 1.25)
			(end -1.051 2)
			(stroke
				(width 0.15)
				(type solid)
			)
			(layer "B.Fab")
		)
		(fp_rect
			(start 1.8 -2.048)
			(end -1.8 2)
			(stroke
				(width 0.15)
				(type solid)
			)
			(fill none)
			(layer "B.Fab")
		)
		(fp_text user "~"
			(at -0.31 -2.7 0)
			(unlocked yes)
			(layer "B.SilkS")
			(effects
				(font
					(size 0.7 0.7)
					(thickness 0.15)
				)
				(justify left bottom mirror)
			)
		)
		(fp_text user "${REFERENCE}"
			(at -2.1 -4.599 0)
			(layer "B.Fab")
			(hide yes)
			(effects
				(font
					(size 0.7 0.7)
					(thickness 0.15)
				)
				(justify left bottom mirror)
			)
		)
		(fp_text user "License: Apache-2.0"
			(at -2.1 -6.599 0)
			(layer "B.Fab")
			(hide yes)
			(effects
				(font
					(size 0.7 0.7)
					(thickness 0.15)
				)
				(justify left bottom mirror)
			)
		)
		(fp_text user "Author: Antmicro"
			(at -2.1 -5.599 0)
			(layer "B.Fab")
			(hide yes)
			(effects
				(font
					(size 0.7 0.7)
					(thickness 0.15)
				)
				(justify left bottom mirror)
			)
		)
		(pad "1" smd roundrect
			(at -1.27 1.85 90)
			(size 1.4 0.48)
			(layers "B.Cu" "B.Paste" "B.Mask")
			(roundrect_rratio 0.25)
			(net 148 "Net-(D12-Pad1)")
			(pinfunction "1")
			(pintype "passive")
		)
		(pad "2" smd roundrect
			(at 1.27 1.85 90)
			(size 1.4 0.48)
			(layers "B.Cu" "B.Paste" "B.Mask")
			(roundrect_rratio 0.25)
			(net 149 "Net-(D12-Pad2)")
			(pinfunction "2")
			(pintype "passive")
		)
		(pad "3" smd roundrect
			(at -1.27 -1.85 90)
			(size 1.4 0.48)
			(layers "B.Cu" "B.Paste" "B.Mask")
			(roundrect_rratio 0.25)
			(net 124 "/Ethernet/PAIR_910")
			(pinfunction "3")
			(pintype "passive")
		)
		(pad "4" smd roundrect
			(at 1.27 -1.85 90)
			(size 1.4 0.48)
			(layers "B.Cu" "B.Paste" "B.Mask")
			(roundrect_rratio 0.25)
			(net 123 "/Ethernet/PAIR_78")
			(pinfunction "4")
			(pintype "passive")
		)
	)
	(footprint "antmicro-footprints:TP_SMD_0.75mm"
		(layer "B.Cu")
		(at 98.14999 103.5508 180)
		(property "Reference" "TP43"
			(at -0.20001 -0.2992 90)
			(layer "B.SilkS")
			(effects
				(font
					(size 0.7 0.7)
					(thickness 0.15)
				)
				(justify left bottom mirror)
			)
		)
		(property "Value" "TP_0.75mm_SMD"
			(at 0 -1.2 0)
			(layer "B.Fab")
			(effects
				(font
					(size 0.7 0.7)
					(thickness 0.15)
				)
				(justify left bottom mirror)
			)
		)
		(property "Footprint" "antmicro-footprints:TP_SMD_0.75mm"
			(at 0 0 180)
			(layer "F.Fab")
			(hide yes)
			(effects
				(font
					(size 1.27 1.27)
					(thickness 0.15)
				)
			)
		)
		(property "Author" "Antmicro"
			(at 196.29998 207.1016 0)
			(layer "B.Fab")
			(hide yes)
			(effects
				(font
					(size 1 1)
					(thickness 0.15)
				)
				(justify mirror)
			)
		)
		(property "License" "Apache-2.0"
			(at 196.29998 207.1016 0)
			(layer "B.Fab")
			(hide yes)
			(effects
				(font
					(size 1 1)
					(thickness 0.15)
				)
				(justify mirror)
			)
		)
		(property "MPN" ""
			(at 196.29998 207.1016 0)
			(layer "B.Fab")
			(hide yes)
			(effects
				(font
					(size 1 1)
					(thickness 0.15)
				)
				(justify mirror)
			)
		)
		(property "Manufacturer" ""
			(at 196.29998 207.1016 0)
			(layer "B.Fab")
			(hide yes)
			(effects
				(font
					(size 1 1)
					(thickness 0.15)
				)
				(justify mirror)
			)
		)
		(sheetname "CSI")
		(sheetfile "csi.kicad_sch")
		(attr exclude_from_pos_files exclude_from_bom)
		(fp_circle
			(center 0 0)
			(end 0.475 0)
			(stroke
				(width 0.05)
				(type default)
			)
			(fill none)
			(layer "B.CrtYd")
		)
		(fp_text user "License: Apache-2.0"
			(at -0.4 -5.101 0)
			(layer "B.Fab")
			(hide yes)
			(effects
				(font
					(size 0.7 0.7)
					(thickness 0.15)
				)
				(justify left bottom mirror)
			)
		)
		(fp_text user "Author: Antmicro"
			(at -0.4 -3.901 0)
			(layer "B.Fab")
			(hide yes)
			(effects
				(font
					(size 0.7 0.7)
					(thickness 0.15)
				)
				(justify left bottom mirror)
			)
		)
		(fp_text user "${REFERENCE}"
			(at -0.4 -2.7 0)
			(layer "B.Fab")
			(hide yes)
			(effects
				(font
					(size 0.7 0.7)
					(thickness 0.15)
				)
				(justify left bottom mirror)
			)
		)
		(pad "1" smd circle
			(at 0 0 180)
			(size 0.75 0.75)
			(layers "B.Cu" "B.Mask")
			(net 544 "/CSI/MUX_I2C_7_SCL")
			(pinfunction "1")
			(pintype "passive")
		)
	)
	(footprint "antmicro-footprints:C_0402_1005Metric"
		(layer "B.Cu")
		(at 94.149999 85.85 90)
		(descr "Capacitor SMD 0402")
		(tags "capacitor SMD 0402")
		(property "Reference" "C47"
			(at -0.8 0.620001 -90)
			(layer "B.SilkS")
			(effects
				(font
					(size 0.7 0.7)
					(thickness 0.15)
				)
				(justify left bottom mirror)
			)
		)
		(property "Value" "C_1u_0402"
			(at 0 -1.4 -90)
			(layer "B.Fab")
			(effects
				(font
					(size 0.7 0.7)
					(thickness 0.15)
				)
				(justify left bottom mirror)
			)
		)
		(property "Footprint" "antmicro-footprints:C_0402_1005Metric"
			(at 0 0 90)
			(layer "F.Fab")
			(hide yes)
			(effects
				(font
					(size 1.27 1.27)
					(thickness 0.15)
				)
			)
		)
		(property "Datasheet" "https://product.tdk.com/en/search/capacitor/ceramic/mlcc/info?part_no=C1005X6S1A105K050BC"
			(at 0 0 90)
			(layer "F.Fab")
			(hide yes)
			(effects
				(font
					(size 1.27 1.27)
					(thickness 0.15)
				)
			)
		)
		(property "Author" "Antmicro"
			(at 179.999999 -8.299999 0)
			(layer "B.Fab")
			(hide yes)
			(effects
				(font
					(size 1 1)
					(thickness 0.15)
				)
				(justify mirror)
			)
		)
		(property "Dielectric" ""
			(at 179.999999 -8.299999 0)
			(layer "B.Fab")
			(hide yes)
			(effects
				(font
					(size 1 1)
					(thickness 0.15)
				)
				(justify mirror)
			)
		)
		(property "License" "Apache-2.0"
			(at 179.999999 -8.299999 0)
			(layer "B.Fab")
			(hide yes)
			(effects
				(font
					(size 1 1)
					(thickness 0.15)
				)
				(justify mirror)
			)
		)
		(property "MPN" "C1005X6S1A105K050BC"
			(at 179.999999 -8.299999 0)
			(layer "B.Fab")
			(hide yes)
			(effects
				(font
					(size 1 1)
					(thickness 0.15)
				)
				(justify mirror)
			)
		)
		(property "Manufacturer" "TDK"
			(at 179.999999 -8.299999 0)
			(layer "B.Fab")
			(hide yes)
			(effects
				(font
					(size 1 1)
					(thickness 0.15)
				)
				(justify mirror)
			)
		)
		(property "Val" "1u"
			(at 179.999999 -8.299999 0)
			(layer "B.Fab")
			(hide yes)
			(effects
				(font
					(size 1 1)
					(thickness 0.15)
				)
				(justify mirror)
			)
		)
		(property "Voltage" ""
			(at 179.999999 -8.299999 0)
			(layer "B.Fab")
			(hide yes)
			(effects
				(font
					(size 1 1)
					(thickness 0.15)
				)
				(justify mirror)
			)
		)
		(sheetname "HDMI")
		(sheetfile "hdmi.kicad_sch")
		(attr smd)
		(fp_rect
			(start -0.925 0.47)
			(end 0.925 -0.47)
			(stroke
				(width 0.05)
				(type default)
			)
			(fill none)
			(layer "B.CrtYd")
		)
		(fp_line
			(start 0.504 -0.248)
			(end 0.504 0.25)
			(stroke
				(width 0.15)
				(type solid)
			)
			(layer "B.Fab")
		)
		(fp_line
			(start -0.494 -0.248)
			(end 0.504 -0.248)
			(stroke
				(width 0.15)
				(type solid)
			)
			(layer "B.Fab")
		)
		(fp_line
			(start 0.504 0.25)
			(end -0.494 0.25)
			(stroke
				(width 0.15)
				(type solid)
			)
			(layer "B.Fab")
		)
		(fp_line
			(start -0.494 0.25)
			(end -0.494 -0.248)
			(stroke
				(width 0.15)
				(type solid)
			)
			(layer "B.Fab")
		)
		(fp_text user "${REFERENCE}"
			(at -0.932 -3.168 -90)
			(layer "B.Fab")
			(hide yes)
			(effects
				(font
					(size 0.7 0.7)
					(thickness 0.15)
				)
				(justify left bottom mirror)
			)
		)
		(fp_text user "Author: Antmicro"
			(at -0.932 -4.17 -90)
			(layer "B.Fab")
			(hide yes)
			(effects
				(font
					(size 0.7 0.7)
					(thickness 0.15)
				)
				(justify left bottom mirror)
			)
		)
		(fp_text user "License: Apache-2.0"
			(at -0.932 -5.17 -90)
			(layer "B.Fab")
			(hide yes)
			(effects
				(font
					(size 0.7 0.7)
					(thickness 0.15)
				)
				(justify left bottom mirror)
			)
		)
		(pad "1" smd roundrect
			(at -0.48 0 90)
			(size 0.59 0.64)
			(layers "B.Cu" "B.Paste" "B.Mask")
			(roundrect_rratio 0.25)
			(net 1 "GND")
			(pintype "passive")
		)
		(pad "2" smd roundrect
			(at 0.48 0 90)
			(size 0.59 0.64)
			(layers "B.Cu" "B.Paste" "B.Mask")
			(roundrect_rratio 0.25)
			(net 87 "+3V3")
			(pintype "passive")
		)
	)
	(footprint "antmicro-footprints:C_0402_1005Metric"
		(layer "B.Cu")
		(at 62.4 109.2 -90)
		(descr "Capacitor SMD 0402")
		(tags "capacitor SMD 0402")
		(property "Reference" "C136"
			(at 0.95 -0.3 90)
			(layer "B.SilkS")
			(effects
				(font
					(size 0.7 0.7)
					(thickness 0.15)
				)
				(justify left bottom mirror)
			)
		)
		(property "Value" "C_4u7_25V_0402"
			(at 0 -1.4 90)
			(layer "B.Fab")
			(effects
				(font
					(size 0.7 0.7)
					(thickness 0.15)
				)
				(justify left bottom mirror)
			)
		)
		(property "Footprint" "antmicro-footprints:C_0402_1005Metric"
			(at 0 0 -90)
			(layer "F.Fab")
			(hide yes)
			(effects
				(font
					(size 1.27 1.27)
					(thickness 0.15)
				)
			)
		)
		(property "Datasheet" "https://www.murata.com/products/productdetail?partno=GRM155C61E475ME15%23"
			(at 0 0 -90)
			(layer "F.Fab")
			(hide yes)
			(effects
				(font
					(size 1.27 1.27)
					(thickness 0.15)
				)
			)
		)
		(property "Author" "Antmicro"
			(at -46.8 171.6 0)
			(layer "B.Fab")
			(hide yes)
			(effects
				(font
					(size 1 1)
					(thickness 0.15)
				)
				(justify mirror)
			)
		)
		(property "Dielectric" "X5S"
			(at -46.8 171.6 0)
			(layer "B.Fab")
			(hide yes)
			(effects
				(font
					(size 1 1)
					(thickness 0.15)
				)
				(justify mirror)
			)
		)
		(property "License" "Apache-2.0"
			(at -46.8 171.6 0)
			(layer "B.Fab")
			(hide yes)
			(effects
				(font
					(size 1 1)
					(thickness 0.15)
				)
				(justify mirror)
			)
		)
		(property "MPN" "GRM155C61E475ME15J"
			(at -46.8 171.6 0)
			(layer "B.Fab")
			(hide yes)
			(effects
				(font
					(size 1 1)
					(thickness 0.15)
				)
				(justify mirror)
			)
		)
		(property "Manufacturer" "Murata"
			(at -46.8 171.6 0)
			(layer "B.Fab")
			(hide yes)
			(effects
				(font
					(size 1 1)
					(thickness 0.15)
				)
				(justify mirror)
			)
		)
		(property "Val" "4u7"
			(at -46.8 171.6 0)
			(layer "B.Fab")
			(hide yes)
			(effects
				(font
					(size 1 1)
					(thickness 0.15)
				)
				(justify mirror)
			)
		)
		(property "Voltage" "25V"
			(at -46.8 171.6 0)
			(layer "B.Fab")
			(hide yes)
			(effects
				(font
					(size 1 1)
					(thickness 0.15)
				)
				(justify mirror)
			)
		)
		(sheetname "USB Debug, DP")
		(sheetfile "usb.kicad_sch")
		(attr smd)
		(fp_rect
			(start -0.925 0.47)
			(end 0.925 -0.47)
			(stroke
				(width 0.05)
				(type default)
			)
			(fill none)
			(layer "B.CrtYd")
		)
		(fp_line
			(start -0.494 0.25)
			(end -0.494 -0.248)
			(stroke
				(width 0.15)
				(type solid)
			)
			(layer "B.Fab")
		)
		(fp_line
			(start 0.504 0.25)
			(end -0.494 0.25)
			(stroke
				(width 0.15)
				(type solid)
			)
			(layer "B.Fab")
		)
		(fp_line
			(start -0.494 -0.248)
			(end 0.504 -0.248)
			(stroke
				(width 0.15)
				(type solid)
			)
			(layer "B.Fab")
		)
		(fp_line
			(start 0.504 -0.248)
			(end 0.504 0.25)
			(stroke
				(width 0.15)
				(type solid)
			)
			(layer "B.Fab")
		)
		(fp_text user "${REFERENCE}"
			(at -0.932 -3.168 90)
			(layer "B.Fab")
			(hide yes)
			(effects
				(font
					(size 0.7 0.7)
					(thickness 0.15)
				)
				(justify left bottom mirror)
			)
		)
		(fp_text user "Author: Antmicro"
			(at -0.932 -4.17 90)
			(layer "B.Fab")
			(hide yes)
			(effects
				(font
					(size 0.7 0.7)
					(thickness 0.15)
				)
				(justify left bottom mirror)
			)
		)
		(fp_text user "License: Apache-2.0"
			(at -0.932 -5.17 90)
			(layer "B.Fab")
			(hide yes)
			(effects
				(font
					(size 0.7 0.7)
					(thickness 0.15)
				)
				(justify left bottom mirror)
			)
		)
		(pad "1" smd roundrect
			(at -0.48 0 270)
			(size 0.59 0.64)
			(layers "B.Cu" "B.Paste" "B.Mask")
			(roundrect_rratio 0.25)
			(net 480 "USBPD1_HV")
			(pintype "passive")
		)
		(pad "2" smd roundrect
			(at 0.48 0 270)
			(size 0.59 0.64)
			(layers "B.Cu" "B.Paste" "B.Mask")
			(roundrect_rratio 0.25)
			(net 1 "GND")
			(pintype "passive")
		)
	)
	(footprint "antmicro-footprints:TP_SMD_0.75mm"
		(layer "B.Cu")
		(at 99.14999 103.5508 180)
		(property "Reference" "TP42"
			(at 0 0.6 0)
			(layer "B.SilkS")
			(hide yes)
			(effects
				(font
					(size 0.7 0.7)
					(thickness 0.15)
				)
				(justify left bottom mirror)
			)
		)
		(property "Value" "TP_0.75mm_SMD"
			(at 0 -1.2 0)
			(layer "B.Fab")
			(effects
				(font
					(size 0.7 0.7)
					(thickness 0.15)
				)
				(justify left bottom mirror)
			)
		)
		(property "Footprint" "antmicro-footprints:TP_SMD_0.75mm"
			(at 0 0 180)
			(layer "F.Fab")
			(hide yes)
			(effects
				(font
					(size 1.27 1.27)
					(thickness 0.15)
				)
			)
		)
		(property "Author" "Antmicro"
			(at 198.29998 207.1016 0)
			(layer "B.Fab")
			(hide yes)
			(effects
				(font
					(size 1 1)
					(thickness 0.15)
				)
				(justify mirror)
			)
		)
		(property "License" "Apache-2.0"
			(at 198.29998 207.1016 0)
			(layer "B.Fab")
			(hide yes)
			(effects
				(font
					(size 1 1)
					(thickness 0.15)
				)
				(justify mirror)
			)
		)
		(property "MPN" ""
			(at 198.29998 207.1016 0)
			(layer "B.Fab")
			(hide yes)
			(effects
				(font
					(size 1 1)
					(thickness 0.15)
				)
				(justify mirror)
			)
		)
		(property "Manufacturer" ""
			(at 198.29998 207.1016 0)
			(layer "B.Fab")
			(hide yes)
			(effects
				(font
					(size 1 1)
					(thickness 0.15)
				)
				(justify mirror)
			)
		)
		(sheetname "CSI")
		(sheetfile "csi.kicad_sch")
		(attr exclude_from_pos_files exclude_from_bom)
		(fp_circle
			(center 0 0)
			(end 0.475 0)
			(stroke
				(width 0.05)
				(type default)
			)
			(fill none)
			(layer "B.CrtYd")
		)
		(fp_text user "${REFERENCE}"
			(at -0.4 -2.7 0)
			(layer "B.Fab")
			(hide yes)
			(effects
				(font
					(size 0.7 0.7)
					(thickness 0.15)
				)
				(justify left bottom mirror)
			)
		)
		(fp_text user "License: Apache-2.0"
			(at -0.4 -5.101 0)
			(layer "B.Fab")
			(hide yes)
			(effects
				(font
					(size 0.7 0.7)
					(thickness 0.15)
				)
				(justify left bottom mirror)
			)
		)
		(fp_text user "Author: Antmicro"
			(at -0.4 -3.901 0)
			(layer "B.Fab")
			(hide yes)
			(effects
				(font
					(size 0.7 0.7)
					(thickness 0.15)
				)
				(justify left bottom mirror)
			)
		)
		(pad "1" smd circle
			(at 0 0 180)
			(size 0.75 0.75)
			(layers "B.Cu" "B.Mask")
			(net 543 "/CSI/MUX_I2C_7_SDA")
			(pinfunction "1")
			(pintype "passive")
		)
	)
)
